(kicad_pcb
	(version 20260206)
	(generator "pcbnew")
	(generator_version "10.0")
	(general
		(thickness 1.6)
		(legacy_teardrops no)
	)
	(paper "A4")
	(title_block
		(title "peb — Lightning_PEB_BRD.brd")
		(comment 1 "Lightning (Wiwynn / Facebook NVMe JBOF) / footprints 471-476 of 2563")
	)
	(layers
		(0 "F.Cu" signal "TOP")
		(4 "In1.Cu" signal "L2GND")
		(6 "In2.Cu" signal "L3")
		(8 "In3.Cu" signal "L4VCC")
		(10 "In4.Cu" signal "L5VCC")
		(12 "In5.Cu" signal "L6")
		(14 "In6.Cu" signal "L7GND")
		(2 "B.Cu" signal "BOTTOM")
		(9 "F.Adhes" user "F.Adhesive")
		(11 "B.Adhes" user "B.Adhesive")
		(13 "F.Paste" user "Package Geometry/Pastemask Top")
		(15 "B.Paste" user "Package Geometry/Pastemask Bottom")
		(5 "F.SilkS" user "Ref Des/Silkscreen Top")
		(7 "B.SilkS" user "Ref Des/Silkscreen Bottom")
		(1 "F.Mask" user "Board Geometry/Soldermask Top")
		(3 "B.Mask" user "Board Geometry/Soldermask Bottom")
		(17 "Dwgs.User" user "User.Drawings")
		(19 "Cmts.User" user "User.Comments")
		(21 "Eco1.User" user "User.Eco1")
		(23 "Eco2.User" user "User.Eco2")
		(25 "Edge.Cuts" user "Board Geometry/Outline")
		(27 "Margin" user)
		(31 "F.CrtYd" user "Package Geometry/Place Bound Top")
		(29 "B.CrtYd" user "Package Geometry/Place Bound Bottom")
		(35 "F.Fab" user "Ref Des/Assembly Top")
		(33 "B.Fab" user "Ref Des/Assembly Bottom")
	)
	(footprint ""
		(layer "F.Cu")
		(at 82.792062 -212.420454 180)
		(property "Reference" "C349"
			(at 0 0 180)
			(layer "F.SilkS")
			(hide yes)
			(effects
				(font
					(size 1.27 1.27)
				)
			)
		)
		(property "Value" "SCD22U10V2KX-1GP"
			(at 1.1811 -2.7051 180)
			(unlocked yes)
			(layer "F.Fab")
			(hide yes)
			(effects
				(font
					(size 1.016 1.016)
					(thickness 0.1524)
				)
			)
		)
		(property "Device Type" "C402H22"
			(at 1.1811 -4.2291 180)
			(unlocked yes)
			(layer "F.Fab")
			(hide yes)
			(effects
				(font
					(size 1.016 1.016)
					(thickness 0.1524)
				)
			)
		)
		(duplicate_pad_numbers_are_jumpers no)
		(fp_rect
			(start -0.4318 0.9525)
			(end 0.4318 -0.9525)
			(stroke
				(width 0)
				(type default)
			)
			(fill no)
			(layer "F.CrtYd")
		)
		(fp_rect
			(start -0.4318 0.9525)
			(end 0.4318 -0.9525)
			(stroke
				(width 0)
				(type default)
			)
			(fill no)
			(layer "F.Fab")
		)
		(pad "1" smd custom
			(at 0 -0.4445 180)
			(size 0.1524 0.1524)
			(layers "F.Cu" "F.Mask" "F.Paste")
			(net "PCIE_TX_CAP_P67")
			(options
				(clearance outline)
				(anchor circle)
			)
			(primitives
				(gr_poly
					(pts
						(arc
							(start 0.3048 -0.2032)
							(mid 0.275042 -0.275042)
							(end 0.2032 -0.3048)
						)
						(arc
							(start -0.2032 -0.3048)
							(mid -0.275042 -0.275042)
							(end -0.3048 -0.2032)
						)
						(arc
							(start -0.3048 0.2032)
							(mid -0.275042 0.275042)
							(end -0.2032 0.3048)
						)
						(arc
							(start 0.2032 0.3048)
							(mid 0.275042 0.275042)
							(end 0.3048 0.2032)
						)
					)
					(width 0)
					(fill yes)
				)
			)
		)
		(pad "2" smd custom
			(at 0 0.4445 180)
			(size 0.1524 0.1524)
			(layers "F.Cu" "F.Mask" "F.Paste")
			(net "PCIE_TX_P67")
			(options
				(clearance outline)
				(anchor circle)
			)
			(primitives
				(gr_poly
					(pts
						(arc
							(start 0.3048 -0.2032)
							(mid 0.275042 -0.275042)
							(end 0.2032 -0.3048)
						)
						(arc
							(start -0.2032 -0.3048)
							(mid -0.275042 -0.275042)
							(end -0.3048 -0.2032)
						)
						(arc
							(start -0.3048 0.2032)
							(mid -0.275042 0.275042)
							(end -0.2032 0.3048)
						)
						(arc
							(start 0.2032 0.3048)
							(mid 0.275042 0.275042)
							(end 0.3048 0.2032)
						)
					)
					(width 0)
					(fill yes)
				)
			)
		)
	)
	(footprint ""
		(layer "F.Cu")
		(at 308.037992 -33.48101 180)
		(property "Reference" "R729"
			(at 0 0 180)
			(layer "F.SilkS")
			(hide yes)
			(effects
				(font
					(size 1.27 1.27)
				)
			)
		)
		(property "Value" "0R2J-2-GP"
			(at 0.064008 -3.993896 180)
			(unlocked yes)
			(layer "F.Fab")
			(hide yes)
			(effects
				(font
					(size 1.016 1.016)
					(thickness 0.1524)
				)
			)
		)
		(property "Device Type" "R402H16"
			(at 0.064008 -5.517896 180)
			(unlocked yes)
			(layer "F.Fab")
			(hide yes)
			(effects
				(font
					(size 1.016 1.016)
					(thickness 0.1524)
				)
			)
		)
		(duplicate_pad_numbers_are_jumpers no)
		(fp_line
			(start 0.508 -0.9398)
			(end -0.508 -0.9398)
			(stroke
				(width 0.1524)
				(type default)
			)
			(layer "F.SilkS")
		)
		(fp_line
			(start -0.508 -0.9398)
			(end -0.508 0.9398)
			(stroke
				(width 0.1524)
				(type default)
			)
			(layer "F.SilkS")
		)
		(fp_rect
			(start -0.508 0.9398)
			(end 0.508 -0.9398)
			(stroke
				(width 0)
				(type default)
			)
			(fill no)
			(layer "F.CrtYd")
		)
		(fp_rect
			(start -0.508 0.9398)
			(end 0.508 -0.9398)
			(stroke
				(width 0)
				(type default)
			)
			(fill no)
			(layer "F.Fab")
		)
		(pad "1" smd custom
			(at 0 -0.4445 180)
			(size 0.1397 0.1397)
			(layers "F.Cu" "F.Mask" "F.Paste")
			(net "8644_USB_DN7")
			(options
				(clearance outline)
				(anchor circle)
			)
			(primitives
				(gr_poly
					(pts
						(arc
							(start -0.1778 -0.2794)
							(mid -0.249642 -0.249642)
							(end -0.2794 -0.1778)
						)
						(arc
							(start -0.2794 0.1778)
							(mid -0.249642 0.249642)
							(end -0.1778 0.2794)
						)
						(arc
							(start 0.1778 0.2794)
							(mid 0.249642 0.249642)
							(end 0.2794 0.1778)
						)
						(arc
							(start 0.2794 -0.1778)
							(mid 0.249642 -0.249642)
							(end 0.1778 -0.2794)
						)
					)
					(width 0)
					(fill yes)
				)
			)
		)
		(pad "2" smd custom
			(at 0 0.4445 180)
			(size 0.1397 0.1397)
			(layers "F.Cu" "F.Mask" "F.Paste")
			(net "P3V3_STBY")
			(options
				(clearance outline)
				(anchor circle)
			)
			(primitives
				(gr_poly
					(pts
						(arc
							(start -0.1778 -0.2794)
							(mid -0.249642 -0.249642)
							(end -0.2794 -0.1778)
						)
						(arc
							(start -0.2794 0.1778)
							(mid -0.249642 0.249642)
							(end -0.1778 0.2794)
						)
						(arc
							(start 0.1778 0.2794)
							(mid 0.249642 0.249642)
							(end 0.2794 0.1778)
						)
						(arc
							(start 0.2794 -0.1778)
							(mid 0.249642 -0.249642)
							(end 0.1778 -0.2794)
						)
					)
					(width 0)
					(fill yes)
				)
			)
		)
	)
	(footprint ""
		(layer "F.Cu")
		(at 349.749872 -5.40004)
		(property "Reference" "PAD3"
			(at 0 0 0)
			(layer "F.SilkS")
			(hide yes)
			(effects
				(font
					(size 1.27 1.27)
				)
			)
		)
		(property "Value" "PAD-3P-GP"
			(at -18.082768 -12.6492 0)
			(unlocked yes)
			(layer "F.Fab")
			(hide yes)
			(effects
				(font
					(size 1.016 1.016)
					(thickness 0.1524)
				)
			)
		)
		(property "Device Type" "HT219X276B8R32-3P-S"
			(at -18.082768 -14.1732 0)
			(unlocked yes)
			(layer "F.Fab")
			(hide yes)
			(effects
				(font
					(size 1.016 1.016)
					(thickness 0.1524)
				)
			)
		)
		(duplicate_pad_numbers_are_jumpers no)
		(fp_poly
			(pts
				(arc
					(start -6.694678 -8.800084)
					(mid -15.305278 -8.800084)
					(end -6.694678 -8.800084)
				)
			)
			(stroke
				(width 0)
				(type default)
			)
			(fill no)
			(layer "B.CrtYd")
		)
		(fp_poly
			(pts
				(arc
					(start 4.3053 -17.599914)
					(mid -4.3053 -17.599914)
					(end 4.3053 -17.599914)
				)
			)
			(stroke
				(width 0)
				(type default)
			)
			(fill no)
			(layer "B.CrtYd")
		)
		(fp_poly
			(pts
				(arc
					(start 4.3053 0)
					(mid -4.3053 0)
					(end 4.3053 0)
				)
			)
			(stroke
				(width 0)
				(type default)
			)
			(fill no)
			(layer "B.CrtYd")
		)
		(fp_poly
			(pts
				(xy -16.304768 5.30479) (xy -16.304768 -22.904704) (xy 6.154674 -22.904704)
				(arc
					(start 6.154674 -13.79982)
					(mid 5.918991 -13.230831)
					(end 5.350002 -12.995148)
				)
				(arc
					(start 4.99999 -12.995148)
					(mid 4.862053 -12.938013)
					(end 4.804918 -12.800076)
				)
				(arc
					(start 4.804918 -4.800092)
					(mid 4.862038 -4.662065)
					(end 4.99999 -4.604766)
				)
				(arc
					(start 5.350002 -4.604766)
					(mid 5.918991 -4.369083)
					(end 6.154674 -3.800094)
				)
				(xy 6.154674 5.30479)
			)
			(stroke
				(width 0)
				(type default)
			)
			(fill no)
			(layer "F.CrtYd")
		)
		(fp_poly
			(pts
				(arc
					(start -6.694678 -8.800084)
					(mid -15.305278 -8.800084)
					(end -6.694678 -8.800084)
				)
			)
			(stroke
				(width 0)
				(type default)
			)
			(fill no)
			(layer "B.Fab")
		)
		(fp_poly
			(pts
				(arc
					(start 4.3053 -17.599914)
					(mid -4.3053 -17.599914)
					(end 4.3053 -17.599914)
				)
			)
			(stroke
				(width 0)
				(type default)
			)
			(fill no)
			(layer "B.Fab")
		)
		(fp_poly
			(pts
				(arc
					(start 4.3053 0)
					(mid -4.3053 0)
					(end 4.3053 0)
				)
			)
			(stroke
				(width 0)
				(type default)
			)
			(fill no)
			(layer "B.Fab")
		)
		(fp_poly
			(pts
				(xy -16.304768 5.30479) (xy -16.304768 -22.904704) (xy 6.154674 -22.904704)
				(arc
					(start 6.154674 -13.79982)
					(mid 5.918991 -13.230831)
					(end 5.350002 -12.995148)
				)
				(arc
					(start 4.99999 -12.995148)
					(mid 4.862053 -12.938013)
					(end 4.804918 -12.800076)
				)
				(arc
					(start 4.804918 -4.800092)
					(mid 4.862038 -4.662065)
					(end 4.99999 -4.604766)
				)
				(arc
					(start 5.350002 -4.604766)
					(mid 5.918991 -4.369083)
					(end 6.154674 -3.800094)
				)
				(xy 6.154674 5.30479)
			)
			(stroke
				(width 0)
				(type default)
			)
			(fill no)
			(layer "F.Fab")
		)
		(pad "1" thru_hole custom
			(at 0 0)
			(size 5.46246 5.46246)
			(drill 3.2004)
			(layers "*.Cu" "*.Mask")
			(remove_unused_layers no)
			(net "GND")
			(clearance -8.816848)
			(thermal_gap 0.3048)
			(options
				(clearance outline)
				(anchor circle)
			)
			(primitives
				(gr_poly
					(pts
						(xy 10.924794 -13.800074) (xy -10.925048 -13.800074) (xy -10.925048 13.79982) (xy 10.924794 13.79982)
						(arc
							(start 10.924794 4.999736)
							(mid 10.778385 4.646273)
							(end 10.424922 4.499864)
						)
						(arc
							(start 10.07491 4.499864)
							(mid 9.721432 4.353291)
							(end 9.575038 3.999738)
						)
						(arc
							(start 9.575038 -4.000246)
							(mid 9.721447 -4.353709)
							(end 10.07491 -4.500118)
						)
						(arc
							(start 10.424922 -4.500118)
							(mid 10.778475 -4.646617)
							(end 10.924794 -5.000244)
						)
					)
					(width 0)
					(fill yes)
				)
			)
			(padstack
				(mode front_inner_back)
				(layer "Inner"
					(shape circle)
					(size 3.6068 3.6068)
					(clearance 0.3048)
				)
				(layer "B.Cu"
					(shape circle)
					(size 8.001 8.001)
					(clearance -1.8923)
				)
			)
		)
		(pad "2" thru_hole circle
			(at -10.999978 -8.800084)
			(size 8.001 8.001)
			(drill 3.2004)
			(layers "*.Cu" "*.Mask")
			(remove_unused_layers no)
			(net "GND")
			(clearance -1.8923)
			(thermal_gap 0.3048)
			(padstack
				(mode front_inner_back)
				(layer "Inner"
					(shape circle)
					(size 3.6068 3.6068)
					(clearance 0.3048)
				)
				(layer "B.Cu"
					(shape circle)
					(size 8.001 8.001)
					(clearance -1.8923)
				)
			)
		)
		(pad "3" thru_hole circle
			(at 0 -17.599914)
			(size 8.001 8.001)
			(drill 3.2004)
			(layers "*.Cu" "*.Mask")
			(remove_unused_layers no)
			(net "GND")
			(clearance -1.8923)
			(thermal_gap 0.3048)
			(padstack
				(mode front_inner_back)
				(layer "Inner"
					(shape circle)
					(size 3.6068 3.6068)
					(clearance 0.3048)
				)
				(layer "B.Cu"
					(shape circle)
					(size 8.001 8.001)
					(clearance -1.8923)
				)
			)
		)
	)
	(footprint ""
		(layer "F.Cu")
		(at 20.447 -145.415 180)
		(property "Reference" "C196"
			(at 0 0 180)
			(layer "F.SilkS")
			(hide yes)
			(effects
				(font
					(size 1.27 1.27)
				)
			)
		)
		(property "Value" "SC100P50V2JN-3GP"
			(at 1.1811 -2.7051 180)
			(unlocked yes)
			(layer "F.Fab")
			(hide yes)
			(effects
				(font
					(size 1.016 1.016)
					(thickness 0.1524)
				)
			)
		)
		(property "Device Type" "C402H22"
			(at 1.1811 -4.2291 180)
			(unlocked yes)
			(layer "F.Fab")
			(hide yes)
			(effects
				(font
					(size 1.016 1.016)
					(thickness 0.1524)
				)
			)
		)
		(duplicate_pad_numbers_are_jumpers no)
		(fp_rect
			(start -0.4318 0.9525)
			(end 0.4318 -0.9525)
			(stroke
				(width 0)
				(type default)
			)
			(fill no)
			(layer "F.CrtYd")
		)
		(fp_rect
			(start -0.4318 0.9525)
			(end 0.4318 -0.9525)
			(stroke
				(width 0)
				(type default)
			)
			(fill no)
			(layer "F.Fab")
		)
		(pad "1" smd custom
			(at 0 -0.4445 180)
			(size 0.1524 0.1524)
			(layers "F.Cu" "F.Mask" "F.Paste")
			(net "MPLLAV33")
			(options
				(clearance outline)
				(anchor circle)
			)
			(primitives
				(gr_poly
					(pts
						(arc
							(start 0.3048 -0.2032)
							(mid 0.275042 -0.275042)
							(end 0.2032 -0.3048)
						)
						(arc
							(start -0.2032 -0.3048)
							(mid -0.275042 -0.275042)
							(end -0.3048 -0.2032)
						)
						(arc
							(start -0.3048 0.2032)
							(mid -0.275042 0.275042)
							(end -0.2032 0.3048)
						)
						(arc
							(start 0.2032 0.3048)
							(mid 0.275042 0.275042)
							(end 0.3048 0.2032)
						)
					)
					(width 0)
					(fill yes)
				)
			)
		)
		(pad "2" smd custom
			(at 0 0.4445 180)
			(size 0.1524 0.1524)
			(layers "F.Cu" "F.Mask" "F.Paste")
			(net "GND")
			(options
				(clearance outline)
				(anchor circle)
			)
			(primitives
				(gr_poly
					(pts
						(arc
							(start 0.3048 -0.2032)
							(mid 0.275042 -0.275042)
							(end 0.2032 -0.3048)
						)
						(arc
							(start -0.2032 -0.3048)
							(mid -0.275042 -0.275042)
							(end -0.3048 -0.2032)
						)
						(arc
							(start -0.3048 0.2032)
							(mid -0.275042 0.275042)
							(end -0.2032 0.3048)
						)
						(arc
							(start 0.2032 0.3048)
							(mid 0.275042 0.275042)
							(end 0.3048 0.2032)
						)
					)
					(width 0)
					(fill yes)
				)
			)
		)
	)
	(footprint ""
		(layer "F.Cu")
		(at 157.877002 -53.240432 90)
		(property "Reference" "PR180"
			(at 0 0 90)
			(layer "F.SilkS")
			(hide yes)
			(effects
				(font
					(size 1.27 1.27)
				)
			)
		)
		(property "Value" "80K6R2F-GP"
			(at 0.064008 -3.993896 90)
			(unlocked yes)
			(layer "F.Fab")
			(hide yes)
			(effects
				(font
					(size 1.016 1.016)
					(thickness 0.1524)
				)
			)
		)
		(property "Device Type" "R402H16"
			(at 0.064008 -5.517896 90)
			(unlocked yes)
			(layer "F.Fab")
			(hide yes)
			(effects
				(font
					(size 1.016 1.016)
					(thickness 0.1524)
				)
			)
		)
		(duplicate_pad_numbers_are_jumpers no)
		(fp_line
			(start 0.508 -0.9398)
			(end -0.508 -0.9398)
			(stroke
				(width 0.1524)
				(type default)
			)
			(layer "F.SilkS")
		)
		(fp_line
			(start -0.508 -0.9398)
			(end -0.508 0.9398)
			(stroke
				(width 0.1524)
				(type default)
			)
			(layer "F.SilkS")
		)
		(fp_rect
			(start -0.508 0.9398)
			(end 0.508 -0.9398)
			(stroke
				(width 0)
				(type default)
			)
			(fill no)
			(layer "F.CrtYd")
		)
		(fp_rect
			(start -0.508 0.9398)
			(end 0.508 -0.9398)
			(stroke
				(width 0)
				(type default)
			)
			(fill no)
			(layer "F.Fab")
		)
		(pad "1" smd custom
			(at 0 -0.4445 90)
			(size 0.1397 0.1397)
			(layers "F.Cu" "F.Mask" "F.Paste")
			(net "P0V9_VFB")
			(options
				(clearance outline)
				(anchor circle)
			)
			(primitives
				(gr_poly
					(pts
						(arc
							(start -0.1778 -0.2794)
							(mid -0.249642 -0.249642)
							(end -0.2794 -0.1778)
						)
						(arc
							(start -0.2794 0.1778)
							(mid -0.249642 0.249642)
							(end -0.1778 0.2794)
						)
						(arc
							(start 0.1778 0.2794)
							(mid 0.249642 0.249642)
							(end 0.2794 0.1778)
						)
						(arc
							(start 0.2794 -0.1778)
							(mid 0.249642 -0.249642)
							(end 0.1778 -0.2794)
						)
					)
					(width 0)
					(fill yes)
				)
			)
		)
		(pad "2" smd custom
			(at 0 0.4445 90)
			(size 0.1397 0.1397)
			(layers "F.Cu" "F.Mask" "F.Paste")
			(net "P0V9_VFB_AVS")
			(options
				(clearance outline)
				(anchor circle)
			)
			(primitives
				(gr_poly
					(pts
						(arc
							(start -0.1778 -0.2794)
							(mid -0.249642 -0.249642)
							(end -0.2794 -0.1778)
						)
						(arc
							(start -0.2794 0.1778)
							(mid -0.249642 0.249642)
							(end -0.1778 0.2794)
						)
						(arc
							(start 0.1778 0.2794)
							(mid 0.249642 0.249642)
							(end 0.2794 0.1778)
						)
						(arc
							(start 0.2794 -0.1778)
							(mid 0.249642 -0.249642)
							(end 0.1778 -0.2794)
						)
					)
					(width 0)
					(fill yes)
				)
			)
		)
	)
	(footprint ""
		(layer "F.Cu")
		(at 256.8702 -15.9766 90)
		(property "Reference" "Q3203"
			(at 0 0 90)
			(layer "F.SilkS")
			(hide yes)
			(effects
				(font
					(size 1.27 1.27)
				)
			)
		)
		(property "Value" "P2003EVG-GP"
			(at 0 -11.1252 90)
			(unlocked yes)
			(layer "F.Fab")
			(hide yes)
			(effects
				(font
					(size 1.016 1.016)
					(thickness 0.1524)
				)
			)
		)
		(property "Device Type" "SOIC8H79"
			(at 0 -12.6492 90)
			(unlocked yes)
			(layer "F.Fab")
			(hide yes)
			(effects
				(font
					(size 1.016 1.016)
					(thickness 0.1524)
				)
			)
		)
		(duplicate_pad_numbers_are_jumpers no)
		(fp_line
			(start 2.1336 -1.4224)
			(end -2.7432 -1.4224)
			(stroke
				(width 0.1524)
				(type default)
			)
			(layer "F.SilkS")
		)
		(fp_line
			(start -2.7432 -1.4224)
			(end -2.7432 1.4224)
			(stroke
				(width 0.1524)
				(type default)
			)
			(layer "F.SilkS")
		)
		(fp_line
			(start -2.7432 -0.508)
			(end -2.2352 0)
			(stroke
				(width 0.1524)
				(type default)
			)
			(layer "F.SilkS")
		)
		(fp_line
			(start -2.2352 0)
			(end -2.7432 0.508)
			(stroke
				(width 0.1524)
				(type default)
			)
			(layer "F.SilkS")
		)
		(fp_line
			(start 2.1336 1.4224)
			(end 2.1336 -1.4224)
			(stroke
				(width 0.1524)
				(type default)
			)
			(layer "F.SilkS")
		)
		(fp_line
			(start -2.7432 1.4224)
			(end 2.1336 1.4224)
			(stroke
				(width 0.1524)
				(type default)
			)
			(layer "F.SilkS")
		)
		(fp_line
			(start -2.6162 3.429)
			(end -2.6162 1.4732)
			(stroke
				(width 0.4064)
				(type default)
			)
			(layer "F.SilkS")
		)
		(fp_poly
			(pts
				(xy 2.2098 -1.4224) (xy 2.2098 1.4224) (xy -2.2225 1.4224) (xy -2.2225 -1.4224)
			)
			(stroke
				(width 0)
				(type default)
			)
			(fill yes)
			(layer "F.SilkS")
		)
		(fp_rect
			(start -2.4511 2.9972)
			(end 2.4511 -2.9972)
			(stroke
				(width 0)
				(type default)
			)
			(fill no)
			(layer "F.CrtYd")
		)
		(fp_poly
			(pts
				(xy -2.8194 3.6322) (xy -2.8194 -3.6322) (xy 2.8194 -3.6322) (xy 2.8194 -2.2987) (xy 2.4511 -2.2987)
				(xy 2.4511 -2.9972) (xy -2.4511 -2.9972) (xy -2.4511 2.9972) (xy 2.4511 2.9972) (xy 2.4511 -2.286)
				(xy 2.8194 -2.286) (xy 2.8194 3.6322)
			)
			(stroke
				(width 0)
				(type default)
			)
			(fill no)
			(layer "F.CrtYd")
		)
		(fp_rect
			(start -2.8194 3.6322)
			(end 2.8194 -3.6322)
			(stroke
				(width 0)
				(type default)
			)
			(fill no)
			(layer "F.Fab")
		)
		(pad "1" smd rect
			(at -1.905 2.54 90)
			(size 0.635 1.651)
			(layers "F.Cu" "F.Mask" "F.Paste")
			(net "P3V3_STBY")
		)
		(pad "2" smd rect
			(at -0.635 2.54 90)
			(size 0.635 1.651)
			(layers "F.Cu" "F.Mask" "F.Paste")
			(net "P3V3_STBY")
		)
		(pad "3" smd rect
			(at 0.635 2.54 90)
			(size 0.635 1.651)
			(layers "F.Cu" "F.Mask" "F.Paste")
			(net "P3V3_STBY")
		)
		(pad "4" smd rect
			(at 1.905 2.54 90)
			(size 0.635 1.651)
			(layers "F.Cu" "F.Mask" "F.Paste")
			(net "Q3203_G")
		)
		(pad "5" smd rect
			(at 1.905 -2.54 90)
			(size 0.635 1.651)
			(layers "F.Cu" "F.Mask" "F.Paste")
			(net "P3V3_GPIO")
		)
		(pad "6" smd rect
			(at 0.635 -2.54 90)
			(size 0.635 1.651)
			(layers "F.Cu" "F.Mask" "F.Paste")
			(net "P3V3_GPIO")
		)
		(pad "7" smd rect
			(at -0.635 -2.54 90)
			(size 0.635 1.651)
			(layers "F.Cu" "F.Mask" "F.Paste")
			(net "P3V3_GPIO")
		)
		(pad "8" smd rect
			(at -1.905 -2.54 90)
			(size 0.635 1.651)
			(layers "F.Cu" "F.Mask" "F.Paste")
			(net "P3V3_GPIO")
		)
	)
)
